(kicad_pcb
	(version 20260206)
	(generator "pcbnew")
	(generator_version "10.0")
	(general
		(thickness 1.6)
		(legacy_teardrops no)
	)
	(paper "A4")
	(title_block
		(title "dpb — 14545-sa.0730WZS0815.brd")
		(comment 1 "Honey Badger (Wiwynn) / footprints 116-122 of 1066")
	)
	(layers
		(0 "F.Cu" signal "TOP")
		(4 "In1.Cu" signal "L2GND")
		(6 "In2.Cu" signal "L3")
		(8 "In3.Cu" signal "L4VCC")
		(10 "In4.Cu" signal "L5VCC")
		(12 "In5.Cu" signal "L6")
		(14 "In6.Cu" signal "L7GND")
		(2 "B.Cu" signal "BOTTOM")
		(9 "F.Adhes" user "F.Adhesive")
		(11 "B.Adhes" user "B.Adhesive")
		(13 "F.Paste" user "Package Geometry/Pastemask Top")
		(15 "B.Paste" user "Package Geometry/Pastemask Bottom")
		(5 "F.SilkS" user "Ref Des/Silkscreen Top")
		(7 "B.SilkS" user "Ref Des/Silkscreen Bottom")
		(1 "F.Mask" user "Board Geometry/Soldermask Top")
		(3 "B.Mask" user "Board Geometry/Soldermask Bottom")
		(17 "Dwgs.User" user "User.Drawings")
		(19 "Cmts.User" user "User.Comments")
		(21 "Eco1.User" user "User.Eco1")
		(23 "Eco2.User" user "User.Eco2")
		(25 "Edge.Cuts" user "Board Geometry/Outline")
		(27 "Margin" user)
		(31 "F.CrtYd" user "Package Geometry/Place Bound Top")
		(29 "B.CrtYd" user "Package Geometry/Place Bound Bottom")
		(35 "F.Fab" user "Ref Des/Assembly Top")
		(33 "B.Fab" user "Ref Des/Assembly Bottom")
	)
	(footprint ""
		(layer "F.Cu")
		(at 33.043368 -469.837516 -90)
		(property "Reference" "C183"
			(at 0 0 270)
			(layer "F.SilkS")
			(hide yes)
			(effects
				(font
					(size 1.27 1.27)
				)
			)
		)
		(property "Value" "SCD01U50V2KX-1GP"
			(at 1.1811 -2.7051 270)
			(unlocked yes)
			(layer "F.Fab")
			(hide yes)
			(effects
				(font
					(size 1.016 1.016)
					(thickness 0.1524)
				)
			)
		)
		(property "Device Type" "C402H22"
			(at 1.1811 -4.2291 270)
			(unlocked yes)
			(layer "F.Fab")
			(hide yes)
			(effects
				(font
					(size 1.016 1.016)
					(thickness 0.1524)
				)
			)
		)
		(duplicate_pad_numbers_are_jumpers no)
		(fp_rect
			(start -0.4318 0.9525)
			(end 0.4318 -0.9525)
			(stroke
				(width 0)
				(type default)
			)
			(fill no)
			(layer "F.CrtYd")
		)
		(fp_rect
			(start -0.4318 0.9525)
			(end 0.4318 -0.9525)
			(stroke
				(width 0)
				(type default)
			)
			(fill no)
			(layer "F.Fab")
		)
		(pad "1" smd custom
			(at 0 -0.4445 270)
			(size 0.1524 0.1524)
			(layers "F.Cu" "F.Mask" "F.Paste")
			(net "SAS2X28_DRIVE_RX_P_A5")
			(options
				(clearance outline)
				(anchor circle)
			)
			(primitives
				(gr_poly
					(pts
						(arc
							(start 0.3048 -0.2032)
							(mid 0.275042 -0.275042)
							(end 0.2032 -0.3048)
						)
						(arc
							(start -0.2032 -0.3048)
							(mid -0.275042 -0.275042)
							(end -0.3048 -0.2032)
						)
						(arc
							(start -0.3048 0.2032)
							(mid -0.275042 0.275042)
							(end -0.2032 0.3048)
						)
						(arc
							(start 0.2032 0.3048)
							(mid 0.275042 0.275042)
							(end 0.3048 0.2032)
						)
					)
					(width 0)
					(fill yes)
				)
			)
		)
		(pad "2" smd custom
			(at 0 0.4445 270)
			(size 0.1524 0.1524)
			(layers "F.Cu" "F.Mask" "F.Paste")
			(net "SAS2X28_A_HDD5_RX_+")
			(options
				(clearance outline)
				(anchor circle)
			)
			(primitives
				(gr_poly
					(pts
						(arc
							(start 0.3048 -0.2032)
							(mid 0.275042 -0.275042)
							(end 0.2032 -0.3048)
						)
						(arc
							(start -0.2032 -0.3048)
							(mid -0.275042 -0.275042)
							(end -0.3048 -0.2032)
						)
						(arc
							(start -0.3048 0.2032)
							(mid -0.275042 0.275042)
							(end -0.2032 0.3048)
						)
						(arc
							(start 0.2032 0.3048)
							(mid 0.275042 0.275042)
							(end 0.3048 0.2032)
						)
					)
					(width 0)
					(fill yes)
				)
			)
		)
	)
	(footprint ""
		(layer "F.Cu")
		(at 200.037446 -457.361036 90)
		(property "Reference" "R354"
			(at 0 0 90)
			(layer "F.SilkS")
			(hide yes)
			(effects
				(font
					(size 1.27 1.27)
				)
			)
		)
		(property "Value" "0R2J-2-GP"
			(at 0.064008 -3.993896 90)
			(unlocked yes)
			(layer "F.Fab")
			(hide yes)
			(effects
				(font
					(size 1.016 1.016)
					(thickness 0.1524)
				)
			)
		)
		(property "Device Type" "R402H16"
			(at 0.064008 -5.517896 90)
			(unlocked yes)
			(layer "F.Fab")
			(hide yes)
			(effects
				(font
					(size 1.016 1.016)
					(thickness 0.1524)
				)
			)
		)
		(duplicate_pad_numbers_are_jumpers no)
		(fp_line
			(start 0.508 -0.9398)
			(end -0.508 -0.9398)
			(stroke
				(width 0.1524)
				(type default)
			)
			(layer "F.SilkS")
		)
		(fp_line
			(start -0.508 -0.9398)
			(end -0.508 0.9398)
			(stroke
				(width 0.1524)
				(type default)
			)
			(layer "F.SilkS")
		)
		(fp_rect
			(start -0.508 0.9398)
			(end 0.508 -0.9398)
			(stroke
				(width 0)
				(type default)
			)
			(fill no)
			(layer "F.CrtYd")
		)
		(fp_rect
			(start -0.508 0.9398)
			(end 0.508 -0.9398)
			(stroke
				(width 0)
				(type default)
			)
			(fill no)
			(layer "F.Fab")
		)
		(pad "1" smd custom
			(at 0 -0.4445 90)
			(size 0.1397 0.1397)
			(layers "F.Cu" "F.Mask" "F.Paste")
			(net "EEPROM_SDA")
			(options
				(clearance outline)
				(anchor circle)
			)
			(primitives
				(gr_poly
					(pts
						(arc
							(start -0.1778 -0.2794)
							(mid -0.249642 -0.249642)
							(end -0.2794 -0.1778)
						)
						(arc
							(start -0.2794 0.1778)
							(mid -0.249642 0.249642)
							(end -0.1778 0.2794)
						)
						(arc
							(start 0.1778 0.2794)
							(mid 0.249642 0.249642)
							(end 0.2794 0.1778)
						)
						(arc
							(start 0.2794 -0.1778)
							(mid 0.249642 -0.249642)
							(end 0.1778 -0.2794)
						)
					)
					(width 0)
					(fill yes)
				)
			)
		)
		(pad "2" smd custom
			(at 0 0.4445 90)
			(size 0.1397 0.1397)
			(layers "F.Cu" "F.Mask" "F.Paste")
			(net "I2C_B_SDA")
			(options
				(clearance outline)
				(anchor circle)
			)
			(primitives
				(gr_poly
					(pts
						(arc
							(start -0.1778 -0.2794)
							(mid -0.249642 -0.249642)
							(end -0.2794 -0.1778)
						)
						(arc
							(start -0.2794 0.1778)
							(mid -0.249642 0.249642)
							(end -0.1778 0.2794)
						)
						(arc
							(start 0.1778 0.2794)
							(mid 0.249642 0.249642)
							(end 0.2794 0.1778)
						)
						(arc
							(start 0.2794 -0.1778)
							(mid 0.249642 -0.249642)
							(end 0.1778 -0.2794)
						)
					)
					(width 0)
					(fill yes)
				)
			)
		)
	)
	(footprint ""
		(layer "F.Cu")
		(at 195.326 -89.916)
		(property "Reference" "C383"
			(at 0 0 0)
			(layer "F.SilkS")
			(hide yes)
			(effects
				(font
					(size 1.27 1.27)
				)
			)
		)
		(property "Value" "SCD033U25V2KX-GP"
			(at 1.1811 -2.7051 0)
			(unlocked yes)
			(layer "F.Fab")
			(hide yes)
			(effects
				(font
					(size 1.016 1.016)
					(thickness 0.1524)
				)
			)
		)
		(property "Device Type" "C402H22"
			(at 1.1811 -4.2291 0)
			(unlocked yes)
			(layer "F.Fab")
			(hide yes)
			(effects
				(font
					(size 1.016 1.016)
					(thickness 0.1524)
				)
			)
		)
		(duplicate_pad_numbers_are_jumpers no)
		(fp_rect
			(start -0.4318 0.9525)
			(end 0.4318 -0.9525)
			(stroke
				(width 0)
				(type default)
			)
			(fill no)
			(layer "F.CrtYd")
		)
		(fp_rect
			(start -0.4318 0.9525)
			(end 0.4318 -0.9525)
			(stroke
				(width 0)
				(type default)
			)
			(fill no)
			(layer "F.Fab")
		)
		(pad "1" smd custom
			(at 0 -0.4445)
			(size 0.1524 0.1524)
			(layers "F.Cu" "F.Mask" "F.Paste")
			(net "P12V")
			(options
				(clearance outline)
				(anchor circle)
			)
			(primitives
				(gr_poly
					(pts
						(arc
							(start 0.3048 -0.2032)
							(mid 0.275042 -0.275042)
							(end 0.2032 -0.3048)
						)
						(arc
							(start -0.2032 -0.3048)
							(mid -0.275042 -0.275042)
							(end -0.3048 -0.2032)
						)
						(arc
							(start -0.3048 0.2032)
							(mid -0.275042 0.275042)
							(end -0.2032 0.3048)
						)
						(arc
							(start 0.2032 0.3048)
							(mid 0.275042 0.275042)
							(end 0.3048 0.2032)
						)
					)
					(width 0)
					(fill yes)
				)
			)
		)
		(pad "2" smd custom
			(at 0 0.4445)
			(size 0.1524 0.1524)
			(layers "F.Cu" "F.Mask" "F.Paste")
			(net "SW_HDD4_N")
			(options
				(clearance outline)
				(anchor circle)
			)
			(primitives
				(gr_poly
					(pts
						(arc
							(start 0.3048 -0.2032)
							(mid 0.275042 -0.275042)
							(end 0.2032 -0.3048)
						)
						(arc
							(start -0.2032 -0.3048)
							(mid -0.275042 -0.275042)
							(end -0.3048 -0.2032)
						)
						(arc
							(start -0.3048 0.2032)
							(mid -0.275042 0.275042)
							(end -0.2032 0.3048)
						)
						(arc
							(start 0.2032 0.3048)
							(mid 0.275042 0.275042)
							(end 0.3048 0.2032)
						)
					)
					(width 0)
					(fill yes)
				)
			)
		)
	)
	(footprint ""
		(layer "F.Cu")
		(at 79.4512 -81.1022)
		(property "Reference" "C253"
			(at 0 0 0)
			(layer "F.SilkS")
			(hide yes)
			(effects
				(font
					(size 1.27 1.27)
				)
			)
		)
		(property "Value" "SCD1U10V2KX-5GP"
			(at 1.1811 -2.7051 0)
			(unlocked yes)
			(layer "F.Fab")
			(hide yes)
			(effects
				(font
					(size 1.016 1.016)
					(thickness 0.1524)
				)
			)
		)
		(property "Device Type" "C402H22"
			(at 1.1811 -4.2291 0)
			(unlocked yes)
			(layer "F.Fab")
			(hide yes)
			(effects
				(font
					(size 1.016 1.016)
					(thickness 0.1524)
				)
			)
		)
		(duplicate_pad_numbers_are_jumpers no)
		(fp_rect
			(start -0.4318 0.9525)
			(end 0.4318 -0.9525)
			(stroke
				(width 0)
				(type default)
			)
			(fill no)
			(layer "F.CrtYd")
		)
		(fp_rect
			(start -0.4318 0.9525)
			(end 0.4318 -0.9525)
			(stroke
				(width 0)
				(type default)
			)
			(fill no)
			(layer "F.Fab")
		)
		(pad "1" smd custom
			(at 0 -0.4445)
			(size 0.1524 0.1524)
			(layers "F.Cu" "F.Mask" "F.Paste")
			(net "P3V3")
			(options
				(clearance outline)
				(anchor circle)
			)
			(primitives
				(gr_poly
					(pts
						(arc
							(start 0.3048 -0.2032)
							(mid 0.275042 -0.275042)
							(end 0.2032 -0.3048)
						)
						(arc
							(start -0.2032 -0.3048)
							(mid -0.275042 -0.275042)
							(end -0.3048 -0.2032)
						)
						(arc
							(start -0.3048 0.2032)
							(mid -0.275042 0.275042)
							(end -0.2032 0.3048)
						)
						(arc
							(start 0.2032 0.3048)
							(mid 0.275042 0.275042)
							(end 0.3048 0.2032)
						)
					)
					(width 0)
					(fill yes)
				)
			)
		)
		(pad "2" smd custom
			(at 0 0.4445)
			(size 0.1524 0.1524)
			(layers "F.Cu" "F.Mask" "F.Paste")
			(net "GND")
			(options
				(clearance outline)
				(anchor circle)
			)
			(primitives
				(gr_poly
					(pts
						(arc
							(start 0.3048 -0.2032)
							(mid 0.275042 -0.275042)
							(end 0.2032 -0.3048)
						)
						(arc
							(start -0.2032 -0.3048)
							(mid -0.275042 -0.275042)
							(end -0.3048 -0.2032)
						)
						(arc
							(start -0.3048 0.2032)
							(mid -0.275042 0.275042)
							(end -0.2032 0.3048)
						)
						(arc
							(start 0.2032 0.3048)
							(mid 0.275042 0.275042)
							(end 0.3048 0.2032)
						)
					)
					(width 0)
					(fill yes)
				)
			)
		)
	)
	(footprint ""
		(layer "F.Cu")
		(at 89.153746 -16.3957 90)
		(property "Reference" "U43"
			(at 0 0 90)
			(layer "F.SilkS")
			(hide yes)
			(effects
				(font
					(size 1.27 1.27)
				)
			)
		)
		(property "Value" "74LVC1G08GW-1-GP"
			(at -2.3368 -8.6868 90)
			(unlocked yes)
			(layer "F.Fab")
			(hide yes)
			(effects
				(font
					(size 1.016 1.016)
					(thickness 0.1524)
				)
			)
		)
		(property "Device Type" "SC70-5H44"
			(at -2.3114 -10.414 90)
			(unlocked yes)
			(layer "F.Fab")
			(hide yes)
			(effects
				(font
					(size 1.016 1.016)
					(thickness 0.1524)
				)
			)
		)
		(duplicate_pad_numbers_are_jumpers no)
		(fp_line
			(start 1.3843 -1.8034)
			(end 1.3843 -1.1176)
			(stroke
				(width 0.3302)
				(type default)
			)
			(layer "F.SilkS")
		)
		(fp_line
			(start 0.6604 -1.8034)
			(end 1.3843 -1.8034)
			(stroke
				(width 0.3302)
				(type default)
			)
			(layer "F.SilkS")
		)
		(fp_line
			(start 1.27 -1.7018)
			(end 1.27 1.7018)
			(stroke
				(width 0.1524)
				(type default)
			)
			(layer "F.SilkS")
		)
		(fp_line
			(start -1.27 -1.7018)
			(end 1.27 -1.7018)
			(stroke
				(width 0.1524)
				(type default)
			)
			(layer "F.SilkS")
		)
		(fp_line
			(start 1.27 1.7018)
			(end -1.27 1.7018)
			(stroke
				(width 0.1524)
				(type default)
			)
			(layer "F.SilkS")
		)
		(fp_line
			(start -1.27 1.7018)
			(end -1.27 -1.7018)
			(stroke
				(width 0.1524)
				(type default)
			)
			(layer "F.SilkS")
		)
		(fp_rect
			(start -1.524 1.9558)
			(end 1.524 -1.9558)
			(stroke
				(width 0)
				(type default)
			)
			(fill no)
			(layer "F.CrtYd")
		)
		(fp_poly
			(pts
				(xy -1.524 -1.9558) (xy 1.524 -1.9558) (xy 1.524 1.9558) (xy -1.524 1.9558)
			)
			(stroke
				(width 0)
				(type default)
			)
			(fill no)
			(layer "F.Fab")
		)
		(pad "1" smd rect
			(at 0.65024 -0.8255 90)
			(size 0.4064 1.2192)
			(layers "F.Cu" "F.Mask" "F.Paste")
			(net "SAS2X28_B_HDD14_FLT")
		)
		(pad "2" smd rect
			(at 0 -0.8255 90)
			(size 0.4064 1.2192)
			(layers "F.Cu" "F.Mask" "F.Paste")
			(net "SAS2X28_A_HDD14_FLT")
		)
		(pad "3" smd rect
			(at -0.65024 -0.8255 90)
			(size 0.4064 1.2192)
			(layers "F.Cu" "F.Mask" "F.Paste")
			(net "GND")
		)
		(pad "4" smd rect
			(at -0.65024 0.8255 90)
			(size 0.4064 1.2192)
			(layers "F.Cu" "F.Mask" "F.Paste")
			(net "FLT_HDD14_DRIVE")
		)
		(pad "5" smd rect
			(at 0.65024 0.8255 90)
			(size 0.4064 1.2192)
			(layers "F.Cu" "F.Mask" "F.Paste")
			(net "P3V3")
		)
	)
	(footprint ""
		(layer "F.Cu")
		(at 60.5282 -272.17624 90)
		(property "Reference" "Q60"
			(at 0 0 90)
			(layer "F.SilkS")
			(hide yes)
			(effects
				(font
					(size 1.27 1.27)
				)
			)
		)
		(property "Value" "2N7002DW-7F-GP"
			(at -2.3622 -8.2042 90)
			(unlocked yes)
			(layer "F.Fab")
			(hide yes)
			(effects
				(font
					(size 1.016 1.016)
					(thickness 0.1524)
				)
			)
		)
		(property "Device Type" "SOT-363H44"
			(at -2.3622 -10.1092 90)
			(unlocked yes)
			(layer "F.Fab")
			(hide yes)
			(effects
				(font
					(size 1.016 1.016)
					(thickness 0.1524)
				)
			)
		)
		(duplicate_pad_numbers_are_jumpers no)
		(fp_line
			(start 1.4478 -1.7018)
			(end -1.4478 -1.7018)
			(stroke
				(width 0.1524)
				(type default)
			)
			(layer "F.SilkS")
		)
		(fp_line
			(start -1.4478 -1.7018)
			(end -1.4478 1.7018)
			(stroke
				(width 0.1524)
				(type default)
			)
			(layer "F.SilkS")
		)
		(fp_line
			(start -1.27 1.524)
			(end -1.27 0.6604)
			(stroke
				(width 0.4826)
				(type default)
			)
			(layer "F.SilkS")
		)
		(fp_line
			(start 1.4478 1.7018)
			(end 1.4478 -1.7018)
			(stroke
				(width 0.1524)
				(type default)
			)
			(layer "F.SilkS")
		)
		(fp_line
			(start -1.4478 1.7018)
			(end 1.4478 1.7018)
			(stroke
				(width 0.1524)
				(type default)
			)
			(layer "F.SilkS")
		)
		(fp_poly
			(pts
				(xy -1.524 -1.778) (xy 1.524 -1.778) (xy 1.524 1.778) (xy -1.524 1.778)
			)
			(stroke
				(width 0)
				(type default)
			)
			(fill no)
			(layer "F.CrtYd")
		)
		(fp_poly
			(pts
				(xy -1.524 -1.778) (xy 1.524 -1.778) (xy 1.524 1.778) (xy -1.524 1.778)
			)
			(stroke
				(width 0)
				(type default)
			)
			(fill no)
			(layer "F.Fab")
		)
		(pad "1" smd rect
			(at -0.65024 0.9398 90)
			(size 0.4064 1.016)
			(layers "F.Cu" "F.Mask" "F.Paste")
			(net "P3V3_HDD7_LED")
		)
		(pad "2" smd rect
			(at 0 0.9398 90)
			(size 0.4064 1.016)
			(layers "F.Cu" "F.Mask" "F.Paste")
			(net "HDD7_LED_G")
		)
		(pad "3" smd rect
			(at 0.65024 0.9398 90)
			(size 0.4064 1.016)
			(layers "F.Cu" "F.Mask" "F.Paste")
			(net "P5VB")
		)
		(pad "4" smd rect
			(at 0.65024 -0.9398 90)
			(size 0.4064 1.016)
			(layers "F.Cu" "F.Mask" "F.Paste")
			(net "P5VB_HDD7_LED")
		)
		(pad "5" smd rect
			(at 0 -0.9398 90)
			(size 0.4064 1.016)
			(layers "F.Cu" "F.Mask" "F.Paste")
			(net "HDD7_LED_G")
		)
		(pad "6" smd rect
			(at -0.65024 -0.9398 90)
			(size 0.4064 1.016)
			(layers "F.Cu" "F.Mask" "F.Paste")
			(net "P3V3")
		)
	)
	(footprint ""
		(layer "F.Cu")
		(at 29.781246 -374.9167 90)
		(property "Reference" "R322"
			(at 0 0 90)
			(layer "F.SilkS")
			(hide yes)
			(effects
				(font
					(size 1.27 1.27)
				)
			)
		)
		(property "Value" "4K7R2J-2-GP"
			(at 0.064008 -3.993896 90)
			(unlocked yes)
			(layer "F.Fab")
			(hide yes)
			(effects
				(font
					(size 1.016 1.016)
					(thickness 0.1524)
				)
			)
		)
		(property "Device Type" "R402H16"
			(at 0.064008 -5.517896 90)
			(unlocked yes)
			(layer "F.Fab")
			(hide yes)
			(effects
				(font
					(size 1.016 1.016)
					(thickness 0.1524)
				)
			)
		)
		(duplicate_pad_numbers_are_jumpers no)
		(fp_line
			(start 0.508 -0.9398)
			(end -0.508 -0.9398)
			(stroke
				(width 0.1524)
				(type default)
			)
			(layer "F.SilkS")
		)
		(fp_line
			(start -0.508 -0.9398)
			(end -0.508 0.9398)
			(stroke
				(width 0.1524)
				(type default)
			)
			(layer "F.SilkS")
		)
		(fp_rect
			(start -0.508 0.9398)
			(end 0.508 -0.9398)
			(stroke
				(width 0)
				(type default)
			)
			(fill no)
			(layer "F.CrtYd")
		)
		(fp_rect
			(start -0.508 0.9398)
			(end 0.508 -0.9398)
			(stroke
				(width 0)
				(type default)
			)
			(fill no)
			(layer "F.Fab")
		)
		(pad "1" smd custom
			(at 0 -0.4445 90)
			(size 0.1397 0.1397)
			(layers "F.Cu" "F.Mask" "F.Paste")
			(net "I2C_B_TMP1_A0")
			(options
				(clearance outline)
				(anchor circle)
			)
			(primitives
				(gr_poly
					(pts
						(arc
							(start -0.1778 -0.2794)
							(mid -0.249642 -0.249642)
							(end -0.2794 -0.1778)
						)
						(arc
							(start -0.2794 0.1778)
							(mid -0.249642 0.249642)
							(end -0.1778 0.2794)
						)
						(arc
							(start 0.1778 0.2794)
							(mid 0.249642 0.249642)
							(end 0.2794 0.1778)
						)
						(arc
							(start 0.2794 -0.1778)
							(mid 0.249642 -0.249642)
							(end 0.1778 -0.2794)
						)
					)
					(width 0)
					(fill yes)
				)
			)
		)
		(pad "2" smd custom
			(at 0 0.4445 90)
			(size 0.1397 0.1397)
			(layers "F.Cu" "F.Mask" "F.Paste")
			(net "GND")
			(options
				(clearance outline)
				(anchor circle)
			)
			(primitives
				(gr_poly
					(pts
						(arc
							(start -0.1778 -0.2794)
							(mid -0.249642 -0.249642)
							(end -0.2794 -0.1778)
						)
						(arc
							(start -0.2794 0.1778)
							(mid -0.249642 0.249642)
							(end -0.1778 0.2794)
						)
						(arc
							(start 0.1778 0.2794)
							(mid 0.249642 0.249642)
							(end 0.2794 0.1778)
						)
						(arc
							(start 0.2794 -0.1778)
							(mid 0.249642 -0.249642)
							(end 0.1778 -0.2794)
						)
					)
					(width 0)
					(fill yes)
				)
			)
		)
	)
)
